# T6G (Grand Teton) — schematic netlist excerpt (pin names and nets, part order shuffled) for the footprints in the layout excerpt that follows; sources: Cadence DE-HDL packaged netlist, KiCad conversion of 04192023_DAF0TMB3IC0_F0TG_MB_C_brd_V02_OCP.brd

R905  Q_RES  0 5% CHIP  pkg 0402LF  page 133 : A = RST_PERST_OCP_SFF_BUF2_N ; B = RST_PERST2_OCP_SFF_N
C6723  Q_CAP_DIFFBUS  DIFF BUS_0.22UF 6.3V 20% X6S  pkg C0201  page 341 : \1\ = P5E_CPU1_P2_TX_BUF_C_DP<15> ; \2\ = P5E_CPU1_P2_TX_BUF_DP<15>
PR187  Q_RES  8.87K 1% EMPTY  pkg 0402LF  page 211 : A = GND ; B = PVDDCR_CPU0_P1_LSET1

(kicad_pcb
	(version 20260206)
	(generator "pcbnew")
	(generator_version "10.0")
	(general
		(thickness 1.6)
		(legacy_teardrops no)
	)
	(paper "A4")
	(title_block
		(title "04192023_DAF0TMB3IC0_F0TG_MB_C_brd_V02_OCP.brd")
		(comment 1 "Grand Teton / footprints 3004-3006 of 8354")
	)
	(layers
		(0 "F.Cu" signal "TOP")
		(4 "In1.Cu" signal "GND")
		(6 "In2.Cu" signal "IN1")
		(8 "In3.Cu" signal "GND1")
		(10 "In4.Cu" signal "IN2")
		(12 "In5.Cu" signal "GND2")
		(14 "In6.Cu" signal "IN3")
		(16 "In7.Cu" signal "GND3")
		(18 "In8.Cu" signal "VCC")
		(20 "In9.Cu" signal "VCC1")
		(22 "In10.Cu" signal "GND4")
		(24 "In11.Cu" signal "IN4")
		(26 "In12.Cu" signal "GND5")
		(28 "In13.Cu" signal "IN5")
		(30 "In14.Cu" signal "GND6")
		(32 "In15.Cu" signal "IN6")
		(34 "In16.Cu" signal "GND7")
		(2 "B.Cu" signal "BOTTOM")
		(9 "F.Adhes" user "F.Adhesive")
		(11 "B.Adhes" user "B.Adhesive")
		(13 "F.Paste" user "Package Geometry/Pastemask Top")
		(15 "B.Paste" user "Package Geometry/Pastemask Bottom")
		(5 "F.SilkS" user "Ref Des/Silkscreen Top")
		(7 "B.SilkS" user "Ref Des/Silkscreen Bottom")
		(1 "F.Mask" user "Board Geometry/Soldermask Top")
		(3 "B.Mask" user "Board Geometry/Soldermask Bottom")
		(17 "Dwgs.User" user "User.Drawings")
		(19 "Cmts.User" user "User.Comments")
		(21 "Eco1.User" user "User.Eco1")
		(23 "Eco2.User" user "User.Eco2")
		(25 "Edge.Cuts" user "Board Geometry/Outline")
		(27 "Margin" user)
		(31 "F.CrtYd" user "Package Geometry/Place Bound Top")
		(29 "B.CrtYd" user "Package Geometry/Place Bound Bottom")
		(35 "F.Fab" user "Ref Des/Assembly Top")
		(33 "B.Fab" user "Ref Des/Assembly Bottom")
	)
	(footprint ""
		(layer "F.Cu")
		(at 83.589114 -177.532284)
		(property "Reference" "PR187"
			(at 0 0 0)
			(layer "F.SilkS")
			(hide yes)
			(effects
				(font
					(size 1.27 1.27)
				)
			)
		)
		(property "Value" ""
			(at 0 0 0)
			(layer "F.Fab")
			(effects
				(font
					(size 1.27 1.27)
				)
			)
		)
		(duplicate_pad_numbers_are_jumpers no)
		(fp_line
			(start -0.7874 -0.4064)
			(end 0.7874 -0.4064)
			(stroke
				(width 0.1524)
				(type default)
			)
			(layer "F.SilkS")
		)
		(fp_line
			(start -0.7874 0.4064)
			(end -0.7874 -0.4064)
			(stroke
				(width 0.1524)
				(type default)
			)
			(layer "F.SilkS")
		)
		(fp_line
			(start 0.7874 -0.4064)
			(end 0.7874 0.4064)
			(stroke
				(width 0.1524)
				(type default)
			)
			(layer "F.SilkS")
		)
		(fp_line
			(start 0.7874 0.4064)
			(end -0.7874 0.4064)
			(stroke
				(width 0.1524)
				(type default)
			)
			(layer "F.SilkS")
		)
		(fp_line
			(start -0.67945 -0.305054)
			(end -0.12065 -0.305054)
			(stroke
				(width 0.1)
				(type default)
			)
			(layer "F.Fab")
		)
		(fp_line
			(start -0.67945 0.3048)
			(end -0.67945 -0.305054)
			(stroke
				(width 0.1)
				(type default)
			)
			(layer "F.Fab")
		)
		(fp_line
			(start -0.12065 -0.305054)
			(end -0.12065 -0.2794)
			(stroke
				(width 0.1)
				(type default)
			)
			(layer "F.Fab")
		)
		(fp_line
			(start -0.12065 -0.2794)
			(end 0.12065 -0.2794)
			(stroke
				(width 0.1)
				(type default)
			)
			(layer "F.Fab")
		)
		(fp_line
			(start -0.12065 0.2794)
			(end -0.12065 0.3048)
			(stroke
				(width 0.1)
				(type default)
			)
			(layer "F.Fab")
		)
		(fp_line
			(start -0.12065 0.3048)
			(end -0.67945 0.3048)
			(stroke
				(width 0.1)
				(type default)
			)
			(layer "F.Fab")
		)
		(fp_line
			(start 0.120396 0.2794)
			(end -0.12065 0.2794)
			(stroke
				(width 0.1)
				(type default)
			)
			(layer "F.Fab")
		)
		(fp_line
			(start 0.120396 0.3048)
			(end 0.120396 0.2794)
			(stroke
				(width 0.1)
				(type default)
			)
			(layer "F.Fab")
		)
		(fp_line
			(start 0.12065 -0.3048)
			(end 0.67945 -0.3048)
			(stroke
				(width 0.1)
				(type default)
			)
			(layer "F.Fab")
		)
		(fp_line
			(start 0.12065 -0.2794)
			(end 0.12065 -0.3048)
			(stroke
				(width 0.1)
				(type default)
			)
			(layer "F.Fab")
		)
		(fp_line
			(start 0.67945 -0.3048)
			(end 0.67945 0.3048)
			(stroke
				(width 0.1)
				(type default)
			)
			(layer "F.Fab")
		)
		(fp_line
			(start 0.67945 0.3048)
			(end 0.120396 0.3048)
			(stroke
				(width 0.1)
				(type default)
			)
			(layer "F.Fab")
		)
		(pad "1" smd circle
			(at -0.40005 0)
			(size 0 0)
			(layers "F.Cu" "F.Mask" "F.Paste")
			(net "GND")
		)
		(pad "2" smd circle
			(at 0.40005 0)
			(size 0 0)
			(layers "F.Cu" "F.Mask" "F.Paste")
			(net "PVDDCR_CPU0_P1_LSET1")
		)
	)
	(footprint ""
		(layer "F.Cu")
		(at 213.919054 -124.604018)
		(property "Reference" "R905"
			(at 0 0 0)
			(layer "F.SilkS")
			(hide yes)
			(effects
				(font
					(size 1.27 1.27)
				)
			)
		)
		(property "Value" ""
			(at 0 0 0)
			(layer "F.Fab")
			(effects
				(font
					(size 1.27 1.27)
				)
			)
		)
		(duplicate_pad_numbers_are_jumpers no)
		(fp_line
			(start -0.7874 -0.4064)
			(end 0.7874 -0.4064)
			(stroke
				(width 0.1524)
				(type default)
			)
			(layer "F.SilkS")
		)
		(fp_line
			(start -0.7874 0.4064)
			(end -0.7874 -0.4064)
			(stroke
				(width 0.1524)
				(type default)
			)
			(layer "F.SilkS")
		)
		(fp_line
			(start 0.7874 -0.4064)
			(end 0.7874 0.4064)
			(stroke
				(width 0.1524)
				(type default)
			)
			(layer "F.SilkS")
		)
		(fp_line
			(start 0.7874 0.4064)
			(end -0.7874 0.4064)
			(stroke
				(width 0.1524)
				(type default)
			)
			(layer "F.SilkS")
		)
		(fp_line
			(start -0.67945 -0.305054)
			(end -0.12065 -0.305054)
			(stroke
				(width 0.1)
				(type default)
			)
			(layer "F.Fab")
		)
		(fp_line
			(start -0.67945 0.3048)
			(end -0.67945 -0.305054)
			(stroke
				(width 0.1)
				(type default)
			)
			(layer "F.Fab")
		)
		(fp_line
			(start -0.12065 -0.305054)
			(end -0.12065 -0.2794)
			(stroke
				(width 0.1)
				(type default)
			)
			(layer "F.Fab")
		)
		(fp_line
			(start -0.12065 -0.2794)
			(end 0.12065 -0.2794)
			(stroke
				(width 0.1)
				(type default)
			)
			(layer "F.Fab")
		)
		(fp_line
			(start -0.12065 0.2794)
			(end -0.12065 0.3048)
			(stroke
				(width 0.1)
				(type default)
			)
			(layer "F.Fab")
		)
		(fp_line
			(start -0.12065 0.3048)
			(end -0.67945 0.3048)
			(stroke
				(width 0.1)
				(type default)
			)
			(layer "F.Fab")
		)
		(fp_line
			(start 0.120396 0.2794)
			(end -0.12065 0.2794)
			(stroke
				(width 0.1)
				(type default)
			)
			(layer "F.Fab")
		)
		(fp_line
			(start 0.120396 0.3048)
			(end 0.120396 0.2794)
			(stroke
				(width 0.1)
				(type default)
			)
			(layer "F.Fab")
		)
		(fp_line
			(start 0.12065 -0.3048)
			(end 0.67945 -0.3048)
			(stroke
				(width 0.1)
				(type default)
			)
			(layer "F.Fab")
		)
		(fp_line
			(start 0.12065 -0.2794)
			(end 0.12065 -0.3048)
			(stroke
				(width 0.1)
				(type default)
			)
			(layer "F.Fab")
		)
		(fp_line
			(start 0.67945 -0.3048)
			(end 0.67945 0.3048)
			(stroke
				(width 0.1)
				(type default)
			)
			(layer "F.Fab")
		)
		(fp_line
			(start 0.67945 0.3048)
			(end 0.120396 0.3048)
			(stroke
				(width 0.1)
				(type default)
			)
			(layer "F.Fab")
		)
		(pad "1" smd circle
			(at -0.40005 0)
			(size 0 0)
			(layers "F.Cu" "F.Mask" "F.Paste")
			(net "RST_PERST_OCP_SFF_BUF2_N")
		)
		(pad "2" smd circle
			(at 0.40005 0)
			(size 0 0)
			(layers "F.Cu" "F.Mask" "F.Paste")
			(net "RST_PERST2_OCP_SFF_N")
		)
	)
	(footprint ""
		(layer "F.Cu")
		(at 161.731706 -408.517344 -90)
		(property "Reference" "C6723"
			(at 0 0 270)
			(layer "F.SilkS")
			(hide yes)
			(effects
				(font
					(size 1.27 1.27)
				)
			)
		)
		(property "Value" ""
			(at 0 0 270)
			(layer "F.Fab")
			(effects
				(font
					(size 1.27 1.27)
				)
			)
		)
		(duplicate_pad_numbers_are_jumpers no)
		(fp_line
			(start -0.299974 0.150114)
			(end -0.299974 -0.150114)
			(stroke
				(width 0.1)
				(type default)
			)
			(layer "F.Fab")
		)
		(fp_line
			(start 0.299974 0.150114)
			(end -0.299974 0.150114)
			(stroke
				(width 0.1)
				(type default)
			)
			(layer "F.Fab")
		)
		(fp_line
			(start -0.299974 -0.150114)
			(end 0.299974 -0.150114)
			(stroke
				(width 0.1)
				(type default)
			)
			(layer "F.Fab")
		)
		(fp_line
			(start 0.299974 -0.150114)
			(end 0.299974 0.150114)
			(stroke
				(width 0.1)
				(type default)
			)
			(layer "F.Fab")
		)
		(pad "1" smd rect
			(at -0.2667 0 270)
			(size 0.3048 0.381)
			(layers "F.Cu" "F.Mask" "F.Paste")
			(net "P5E_CPU1_P2_TX_BUF_C_DP<15>")
		)
		(pad "2" smd rect
			(at 0.2667 0 270)
			(size 0.3048 0.381)
			(layers "F.Cu" "F.Mask" "F.Paste")
			(net "P5E_CPU1_P2_TX_BUF_DP<15>")
		)
	)
)
